FILE_TYPE = CONNECTIVITY;
{Allegro Design Entry HDL 17.4-2019 S026 (4007227) 1/17/2022}
"PAGE_NUMBER" = 44;
0"NC";
1"M_H_CPU1_SA_DQ<31:0>";
2"M_H_CPU1_SB_DQ<31:0>";
3"M_H_CPU1_SA_CB<7:0>";
4"M_H_CPU1_SB_CB<7:0>";
5"M_H_CPU1_SA_DQS_DN<9:0>";
6"M_H_CPU1_SA_DQS_DP<9:0>";
7"M_H_CPU1_SB_DQS_DN<9:0>";
8"M_H_CPU1_SB_DQS_DP<9:0>";
9"M_H_CPU1_SA_CA<6:0>";
10"M_H_CPU1_SB_CA<6:0>";
11"M_H_CPU1_ALERT_N";
12"M_H_CPU1_ALERT_R_N";
13"TP_M_H_CPU1_SA_TEST39H";
14"M_H_CPU1_CLK_DN<0>";
15"M_H_CPU1_CLK_DP<0>";
16"M_H_CPU1_SA_CS_N<0>";
17"M_H_CPU1_SA_CS_N<1>";
18"M_H_CPU1_SA_RSP<0>";
19"M_H_CPU1_SA_PAR";
20"M_H_CPU1_SB_CS_N<1>";
21"M_H_CPU1_SB_CS_N<0>";
22"M_H_CPU1_SB_RSP<0>";
23"M_H_CPU1_SB_PAR";
24"M_H_CPU1_RESET_N";
25"M_H_CPU1_SB_CA<6>";
26"M_H_CPU1_SB_DQS_DP<9>";
27"M_H_CPU1_SB_DQS_DP<8>";
28"M_H_CPU1_SB_DQS_DN<9>";
29"M_H_CPU1_SB_DQS_DN<8>";
30"M_H_CPU1_SA_CA<6>";
31"M_H_CPU1_SB_CA<5>";
32"M_H_CPU1_SA_CA<5>";
33"M_H_CPU1_SB_CA<4>";
34"M_H_CPU1_SA_CA<4>";
35"M_H_CPU1_SB_CA<3>";
36"M_H_CPU1_SA_CA<3>";
37"M_H_CPU1_SB_CA<2>";
38"M_H_CPU1_SA_CA<2>";
39"M_H_CPU1_SB_CA<1>";
40"M_H_CPU1_SA_CA<1>";
41"M_H_CPU1_SB_CA<0>";
42"M_H_CPU1_SA_CA<0>";
43"M_H_CPU1_SB_DQS_DP<7>";
44"M_H_CPU1_SB_DQS_DP<6>";
45"M_H_CPU1_SB_DQS_DP<5>";
46"M_H_CPU1_SB_DQS_DP<4>";
47"M_H_CPU1_SA_DQS_DP<9>";
48"M_H_CPU1_SB_DQS_DP<3>";
49"M_H_CPU1_SB_DQS_DN<7>";
50"M_H_CPU1_SA_DQS_DP<8>";
51"M_H_CPU1_SB_DQS_DP<2>";
52"M_H_CPU1_SB_DQS_DN<6>";
53"M_H_CPU1_SB_DQS_DP<1>";
54"M_H_CPU1_SB_DQS_DN<5>";
55"M_H_CPU1_SB_DQS_DP<0>";
56"M_H_CPU1_SB_DQS_DN<4>";
57"M_H_CPU1_SA_DQS_DN<9>";
58"M_H_CPU1_SB_DQS_DN<3>";
59"M_H_CPU1_SA_DQS_DN<8>";
60"M_H_CPU1_SB_DQS_DN<2>";
61"M_H_CPU1_SB_DQS_DN<1>";
62"M_H_CPU1_SB_DQS_DN<0>";
63"M_H_CPU1_SA_DQS_DN<1>";
64"M_H_CPU1_SA_DQS_DN<0>";
65"M_H_CPU1_SA_DQS_DP<7>";
66"M_H_CPU1_SA_DQS_DP<6>";
67"M_H_CPU1_SA_DQS_DP<5>";
68"M_H_CPU1_SA_DQS_DP<4>";
69"M_H_CPU1_SA_DQS_DP<3>";
70"M_H_CPU1_SA_DQS_DN<7>";
71"M_H_CPU1_SA_DQS_DP<2>";
72"M_H_CPU1_SA_DQS_DN<6>";
73"M_H_CPU1_SA_DQS_DP<1>";
74"M_H_CPU1_SA_DQS_DN<5>";
75"M_H_CPU1_SA_DQS_DP<0>";
76"M_H_CPU1_SA_DQS_DN<4>";
77"M_H_CPU1_SA_DQS_DN<3>";
78"M_H_CPU1_SA_DQS_DN<2>";
79"M_H_CPU1_SB_CB<7>";
80"M_H_CPU1_SB_CB<6>";
81"M_H_CPU1_SB_CB<5>";
82"M_H_CPU1_SB_CB<4>";
83"M_H_CPU1_SB_CB<3>";
84"M_H_CPU1_SB_CB<2>";
85"M_H_CPU1_SA_CB<7>";
86"M_H_CPU1_SB_CB<1>";
87"M_H_CPU1_SA_CB<6>";
88"M_H_CPU1_SB_CB<0>";
89"M_H_CPU1_SA_CB<5>";
90"M_H_CPU1_SB_DQ<30>";
91"M_H_CPU1_SA_CB<4>";
92"M_H_CPU1_SA_CB<3>";
93"M_H_CPU1_SA_CB<2>";
94"M_H_CPU1_SA_CB<1>";
95"M_H_CPU1_SA_CB<0>";
96"M_H_CPU1_SB_DQ<19>";
97"M_H_CPU1_SB_DQ<29>";
98"M_H_CPU1_SB_DQ<28>";
99"M_H_CPU1_SB_DQ<27>";
100"M_H_CPU1_SB_DQ<26>";
101"M_H_CPU1_SB_DQ<25>";
102"M_H_CPU1_SB_DQ<24>";
103"M_H_CPU1_SB_DQ<23>";
104"M_H_CPU1_SB_DQ<22>";
105"M_H_CPU1_SB_DQ<21>";
106"M_H_CPU1_SB_DQ<20>";
107"M_H_CPU1_SB_DQ<31>";
108"M_H_CPU1_SB_DQ<9>";
109"M_H_CPU1_SB_DQ<8>";
110"M_H_CPU1_SB_DQ<7>";
111"M_H_CPU1_SB_DQ<6>";
112"M_H_CPU1_SB_DQ<5>";
113"M_H_CPU1_SB_DQ<4>";
114"M_H_CPU1_SB_DQ<18>";
115"M_H_CPU1_SB_DQ<3>";
116"M_H_CPU1_SB_DQ<17>";
117"M_H_CPU1_SB_DQ<2>";
118"M_H_CPU1_SB_DQ<16>";
119"M_H_CPU1_SB_DQ<1>";
120"M_H_CPU1_SB_DQ<15>";
121"M_H_CPU1_SB_DQ<14>";
122"M_H_CPU1_SB_DQ<13>";
123"M_H_CPU1_SB_DQ<12>";
124"M_H_CPU1_SB_DQ<11>";
125"M_H_CPU1_SB_DQ<10>";
126"M_H_CPU1_SA_DQ<25>";
127"M_H_CPU1_SA_DQ<24>";
128"M_H_CPU1_SA_DQ<23>";
129"M_H_CPU1_SA_DQ<22>";
130"M_H_CPU1_SA_DQ<21>";
131"M_H_CPU1_SA_DQ<20>";
132"M_H_CPU1_SA_DQ<31>";
133"M_H_CPU1_SA_DQ<30>";
134"M_H_CPU1_SB_DQ<0>";
135"M_H_CPU1_SA_DQ<19>";
136"M_H_CPU1_SA_DQ<18>";
137"M_H_CPU1_SA_DQ<29>";
138"M_H_CPU1_SA_DQ<17>";
139"M_H_CPU1_SA_DQ<28>";
140"M_H_CPU1_SA_DQ<16>";
141"M_H_CPU1_SA_DQ<27>";
142"M_H_CPU1_SA_DQ<15>";
143"M_H_CPU1_SA_DQ<26>";
144"M_H_CPU1_SA_DQ<14>";
145"M_H_CPU1_SA_DQ<13>";
146"M_H_CPU1_SA_DQ<9>";
147"M_H_CPU1_SA_DQ<12>";
148"M_H_CPU1_SA_DQ<8>";
149"M_H_CPU1_SA_DQ<11>";
150"M_H_CPU1_SA_DQ<7>";
151"M_H_CPU1_SA_DQ<10>";
152"M_H_CPU1_SA_DQ<6>";
153"M_H_CPU1_SA_DQ<5>";
154"M_H_CPU1_SA_DQ<4>";
155"M_H_CPU1_SA_DQ<3>";
156"M_H_CPU1_SA_DQ<2>";
157"M_H_CPU1_SA_DQ<1>";
158"M_H_CPU1_SA_DQ<0>";
%"GENOA_SP5"
"8","(-4625,3525)","0","pure_quanta","I159";
;
LOCATION"U26"
$SEC"8"
CDS_SEC"8"
PART_TYPE"SMLF"
MATERIAL"IO"
VALUE"SOCKET6096_13568-001"
CDS_LIB"pure_quanta"
CDS_LMAN_SYM_OUTLINE"-650,2525,650,-2525"
NEEDS_NO_SIZE"TRUE"
PART_NUMBER"DGA^6000030";
"TEST39H"
$PN"BF14"13;
"MH1_CLK_L"
$PN"BG12"0;
"MH1_CLK_H"
$PN"BF13"0;
"MH0_CLK_L"
$PN"BD13"14;
"MH0_CLK_H"
$PN"BC12"15;
"MHB_PAR"
$PN"BL14"23;
"MHA_PAR"
$PN"BC14"19;
"MHB_DQS_H9"
$PN"BV13"26;
"MHA_CHECK5"
$PN"AP14"89;
"MHA_DATA14"
$PN"T13"144;
"MHA_DATA25"
$PN"AD14"126;
"MHA_DQS_L1"
$PN"P13"63;
"MHB0_CS_L1"
$PN"BN12"20;
"MHB1_CS_L0"
$PN"BL12"0;
"MHB_DATA30"
$PN"DE12"90;
"MHB_DQS_H8"
$PN"DD14"27;
"MHA_CHECK4"
$PN"AN12"91;
"MHA_DATA13"
$PN"T14"145;
"MHA_DATA24"
$PN"AC12"127;
"MHA_DQS_L0"
$PN"H13"64;
"MHB0_CS_L0"
$PN"BM14"21;
"MHB_DQS_H7"
$PN"CV14"43;
"MHA_CHECK3"
$PN"AL14"92;
"MHA_DATA9"
$PN"M14"146;
"MHA_DATA12"
$PN"R12"147;
"MHA_DATA23"
$PN"AC14"128;
"MHB_DATA9"
$PN"CJ14"108;
"MHB_DQS_H6"
$PN"CM14"44;
"MHA_CHECK2"
$PN"AK13"93;
"MHA_DATA8"
$PN"L12"148;
"MHA_DATA11"
$PN"N14"149;
"MHA_DATA22"
$PN"AB13"129;
"MHB_DATA8"
$PN"CH13"109;
"MHB_DQS_H5"
$PN"CF14"45;
"MHB_DQS_L9"
$PN"BW12"28;
"MHA_CHECK1"
$PN"AK14"94;
"MHA_DATA7"
$PN"L14"150;
"MHA_DATA10"
$PN"M13"151;
"MHA_DATA21"
$PN"AB14"130;
"MHB_DATA7"
$PN"CH14"110;
"MHB_DQS_H4"
$PN"BY14"46;
"MHB_DQS_L8"
$PN"DC14"29;
"MHA1_CS_L1"
$PN"AW14"0;
"MHA_CHECK0"
$PN"AJ12"95;
"MHA_DATA6"
$PN"K13"152;
"MHA_DATA20"
$PN"AA12"131;
"MHA_DATA31"
$PN"AJ14"132;
"MHA_DQS_H9"
$PN"AN14"47;
"MHB_DATA6"
$PN"CG12"111;
"MHB_DQS_H3"
$PN"DB13"48;
"MHB_DQS_L7"
$PN"CU14"49;
"MHA0_CS_L1"
$PN"AV14"17;
"MHA1_CS_L0"
$PN"AV13"0;
"MHA_DATA5"
$PN"K14"153;
"MHA_DATA30"
$PN"AH13"133;
"MHA_DQS_H8"
$PN"AG14"50;
"MHB_DATA5"
$PN"CG14"112;
"MHB_DATA19"
$PN"CT14"96;
"MHB_DQS_H2"
$PN"CT13"51;
"MHB_DQS_L6"
$PN"CL14"52;
"MHA0_CS_L0"
$PN"AU12"16;
"MHA_DATA4"
$PN"J12"154;
"MHA_DQS_H7"
$PN"AA14"65;
"MHB_CA6"
$PN"BK13"25;
"MHB_DATA4"
$PN"CF13"113;
"MHB_DATA18"
$PN"CR12"114;
"MHB_DATA29"
$PN"DE14"97;
"MHB_DQS_H1"
$PN"CK13"53;
"MHB_DQS_L5"
$PN"CE14"54;
"MHA_CA6"
$PN"BB14"30;
"MHA_DATA3"
$PN"G14"155;
"MHA_DQS_H6"
$PN"R14"66;
"MHB1_RSP_L"
$PN"BR12"0;
"MHB_CA5"
$PN"BK14"31;
"MHB_DATA3"
$PN"CD14"115;
"MHB_DATA17"
$PN"CR14"116;
"MHB_DATA28"
$PN"DD13"98;
"MHB_DQS_H0"
$PN"CD13"55;
"MHB_DQS_L4"
$PN"BW14"56;
"MHA_CA5"
$PN"BB13"32;
"MHA_DATA2"
$PN"F13"156;
"MHA_DQS_H5"
$PN"J14"67;
"MHA_DQS_L9"
$PN"AM14"57;
"MHB0_RSP_L"
$PN"BP13"22;
"MHB_CA4"
$PN"BJ14"33;
"MHB_CHECK7"
$PN"BV14"79;
"MHB_DATA2"
$PN"CC12"117;
"MHB_DATA16"
$PN"CP13"118;
"MHB_DATA27"
$PN"DB14"99;
"MHB_DQS_L3"
$PN"DC12"58;
"MHA_CA4"
$PN"BA12"34;
"MHA_DATA1"
$PN"F14"157;
"MHA_DQS_H4"
$PN"AL12"68;
"MHA_DQS_L8"
$PN"AF14"59;
"MHB_CA3"
$PN"BJ12"35;
"MHB_CHECK6"
$PN"BU12"80;
"MHB_DATA1"
$PN"CC14"119;
"MHB_DATA15"
$PN"CP14"120;
"MHB_DATA26"
$PN"DA12"100;
"MHB_DQS_L2"
$PN"CU12"60;
"MHA_CA3"
$PN"BA14"36;
"MHA_DATA0"
$PN"E12"158;
"MHA_DQS_H3"
$PN"AE12"69;
"MHA_DQS_L7"
$PN"Y14"70;
"MHB_CA2"
$PN"BH13"37;
"MHB_CHECK5"
$PN"BU14"81;
"MHB_DATA0"
$PN"CB13"134;
"MHB_DATA14"
$PN"CN12"121;
"MHB_DATA25"
$PN"DA14"101;
"MHB_DQS_L1"
$PN"CL12"61;
"MHA_CA2"
$PN"AY14"38;
"MHA_DATA19"
$PN"W14"135;
"MHA_DQS_H2"
$PN"W12"71;
"MHA_DQS_L6"
$PN"P14"72;
"MHB_CA1"
$PN"BH14"39;
"MHB_CHECK4"
$PN"BT13"82;
"MHB_DATA13"
$PN"CN14"122;
"MHB_DATA24"
$PN"CY13"102;
"MHB_DQS_L0"
$PN"CE12"62;
"MHA_CA1"
$PN"AY13"40;
"MHA_DATA18"
$PN"V13"136;
"MHA_DATA29"
$PN"AH14"137;
"MHA_DQS_H1"
$PN"N12"73;
"MHA_DQS_L5"
$PN"H14"74;
"MHB_CA0"
$PN"BG14"41;
"MHB_CHECK3"
$PN"CB14"83;
"MHB_DATA12"
$PN"CM13"123;
"MHB_DATA23"
$PN"CY14"103;
"MHA1_RSP_L"
$PN"BP14"0;
"MHA_CA0"
$PN"AW12"42;
"MHA_DATA17"
$PN"V14"138;
"MHA_DATA28"
$PN"AG12"139;
"MHA_DQS_H0"
$PN"G12"75;
"MHA_DQS_L4"
$PN"AM13"76;
"MHB_CHECK2"
$PN"CA12"84;
"MHB_DATA11"
$PN"CK14"124;
"MHB_DATA22"
$PN"CW12"104;
"MHA0_RSP_L"
$PN"BN14"18;
"MHA_CHECK7"
$PN"AR14"85;
"MHA_DATA16"
$PN"U12"140;
"MHA_DATA27"
$PN"AE14"141;
"MHA_DQS_L3"
$PN"AF13"77;
"MHB_CHECK1"
$PN"CA14"86;
"MHB_DATA10"
$PN"CJ12"125;
"MHB_DATA21"
$PN"CW14"105;
"MHA_CHECK6"
$PN"AP13"87;
"MHA_DATA15"
$PN"U14"142;
"MHA_DATA26"
$PN"AD13"143;
"MHA_DQS_L2"
$PN"Y13"78;
"MHB1_CS_L1"
$PN"BM13"0;
"MHB_CHECK0"
$PN"BY13"88;
"MHB_DATA20"
$PN"CV13"106;
"MHB_DATA31"
$PN"DF14"107;
"MH_RESET_L"
$PN"AU14"24;
"MH_ALERT_L"
$PN"AT14"12;
%"TAP"
"1","(-3350,5900)","0","mstr_standard","I161";
;
CDS_LIB"mstr_standard"
BODY_TYPE"PLUMBING"
HDL_TAP"TRUE";
"B \NAC \NWC"1;
"S \NAC"
BN"0"158;
%"TAP"
"1","(-3350,5800)","0","mstr_standard","I162";
;
CDS_LIB"mstr_standard"
BODY_TYPE"PLUMBING"
HDL_TAP"TRUE";
"B \NAC \NWC"1;
"S \NAC"
BN"2"156;
%"TAP"
"1","(-3350,5850)","0","mstr_standard","I163";
;
CDS_LIB"mstr_standard"
BODY_TYPE"PLUMBING"
HDL_TAP"TRUE";
"B \NAC \NWC"1;
"S \NAC"
BN"1"157;
%"TAP"
"1","(-3350,5750)","0","mstr_standard","I164";
;
CDS_LIB"mstr_standard"
BODY_TYPE"PLUMBING"
HDL_TAP"TRUE";
"B \NAC \NWC"1;
"S \NAC"
BN"3"155;
%"TAP"
"1","(-3350,5700)","0","mstr_standard","I165";
;
CDS_LIB"mstr_standard"
BODY_TYPE"PLUMBING"
HDL_TAP"TRUE";
"B \NAC \NWC"1;
"S \NAC"
BN"4"154;
%"TAP"
"1","(-3350,5650)","0","mstr_standard","I166";
;
CDS_LIB"mstr_standard"
BODY_TYPE"PLUMBING"
HDL_TAP"TRUE";
"B \NAC \NWC"1;
"S \NAC"
BN"5"153;
%"TAP"
"1","(-3350,5400)","0","mstr_standard","I167";
;
CDS_LIB"mstr_standard"
BODY_TYPE"PLUMBING"
HDL_TAP"TRUE";
"B \NAC \NWC"1;
"S \NAC"
BN"9"146;
%"TAP"
"1","(-3350,5550)","0","mstr_standard","I168";
;
CDS_LIB"mstr_standard"
BODY_TYPE"PLUMBING"
HDL_TAP"TRUE";
"B \NAC \NWC"1;
"S \NAC"
BN"7"150;
%"TAP"
"1","(-3350,5600)","0","mstr_standard","I169";
;
CDS_LIB"mstr_standard"
BODY_TYPE"PLUMBING"
HDL_TAP"TRUE";
"B \NAC \NWC"1;
"S \NAC"
BN"6"152;
%"TAP"
"1","(-3350,5450)","0","mstr_standard","I170";
;
CDS_LIB"mstr_standard"
BODY_TYPE"PLUMBING"
HDL_TAP"TRUE";
"B \NAC \NWC"1;
"S \NAC"
BN"8"148;
%"TAP"
"1","(-3350,5350)","0","mstr_standard","I171";
;
CDS_LIB"mstr_standard"
BODY_TYPE"PLUMBING"
HDL_TAP"TRUE";
"B \NAC \NWC"1;
"S \NAC"
BN"10"151;
%"TAP"
"1","(-3350,5250)","0","mstr_standard","I172";
;
CDS_LIB"mstr_standard"
BODY_TYPE"PLUMBING"
HDL_TAP"TRUE";
"B \NAC \NWC"1;
"S \NAC"
BN"12"147;
%"TAP"
"1","(-3350,5300)","0","mstr_standard","I173";
;
CDS_LIB"mstr_standard"
BODY_TYPE"PLUMBING"
HDL_TAP"TRUE";
"B \NAC \NWC"1;
"S \NAC"
BN"11"149;
%"TAP"
"1","(-3350,5150)","0","mstr_standard","I174";
;
CDS_LIB"mstr_standard"
BODY_TYPE"PLUMBING"
HDL_TAP"TRUE";
"B \NAC \NWC"1;
"S \NAC"
BN"14"144;
%"TAP"
"1","(-3350,5200)","0","mstr_standard","I175";
;
CDS_LIB"mstr_standard"
BODY_TYPE"PLUMBING"
HDL_TAP"TRUE";
"B \NAC \NWC"1;
"S \NAC"
BN"13"145;
%"TAP"
"1","(-3350,5000)","0","mstr_standard","I176";
;
CDS_LIB"mstr_standard"
BODY_TYPE"PLUMBING"
HDL_TAP"TRUE";
"B \NAC \NWC"1;
"S \NAC"
BN"16"140;
%"TAP"
"1","(-3350,5100)","0","mstr_standard","I177";
;
CDS_LIB"mstr_standard"
BODY_TYPE"PLUMBING"
HDL_TAP"TRUE";
"B \NAC \NWC"1;
"S \NAC"
BN"15"142;
%"TAP"
"1","(-3350,4900)","0","mstr_standard","I178";
;
CDS_LIB"mstr_standard"
BODY_TYPE"PLUMBING"
HDL_TAP"TRUE";
"B \NAC \NWC"1;
"S \NAC"
BN"18"136;
%"TAP"
"1","(-3350,4950)","0","mstr_standard","I179";
;
CDS_LIB"mstr_standard"
BODY_TYPE"PLUMBING"
HDL_TAP"TRUE";
"B \NAC \NWC"1;
"S \NAC"
BN"17"138;
%"TAP"
"1","(-3350,4800)","0","mstr_standard","I180";
;
CDS_LIB"mstr_standard"
BODY_TYPE"PLUMBING"
HDL_TAP"TRUE";
"B \NAC \NWC"1;
"S \NAC"
BN"20"131;
%"TAP"
"1","(-3350,4850)","0","mstr_standard","I181";
;
CDS_LIB"mstr_standard"
BODY_TYPE"PLUMBING"
HDL_TAP"TRUE";
"B \NAC \NWC"1;
"S \NAC"
BN"19"135;
%"TAP"
"1","(-3350,4750)","0","mstr_standard","I182";
;
CDS_LIB"mstr_standard"
BODY_TYPE"PLUMBING"
HDL_TAP"TRUE";
"B \NAC \NWC"1;
"S \NAC"
BN"21"130;
%"TAP"
"1","(-3350,4650)","0","mstr_standard","I183";
;
CDS_LIB"mstr_standard"
BODY_TYPE"PLUMBING"
HDL_TAP"TRUE";
"B \NAC \NWC"1;
"S \NAC"
BN"23"128;
%"TAP"
"1","(-3350,4700)","0","mstr_standard","I184";
;
CDS_LIB"mstr_standard"
BODY_TYPE"PLUMBING"
HDL_TAP"TRUE";
"B \NAC \NWC"1;
"S \NAC"
BN"22"129;
%"TAP"
"1","(-3350,4550)","0","mstr_standard","I185";
;
CDS_LIB"mstr_standard"
BODY_TYPE"PLUMBING"
HDL_TAP"TRUE";
"B \NAC \NWC"1;
"S \NAC"
BN"24"127;
%"TAP"
"1","(-3350,4500)","0","mstr_standard","I186";
;
CDS_LIB"mstr_standard"
BODY_TYPE"PLUMBING"
HDL_TAP"TRUE";
"B \NAC \NWC"1;
"S \NAC"
BN"25"126;
%"TAP"
"1","(-3350,4400)","0","mstr_standard","I187";
;
CDS_LIB"mstr_standard"
BODY_TYPE"PLUMBING"
HDL_TAP"TRUE";
"B \NAC \NWC"1;
"S \NAC"
BN"27"141;
%"TAP"
"1","(-3350,4450)","0","mstr_standard","I188";
;
CDS_LIB"mstr_standard"
BODY_TYPE"PLUMBING"
HDL_TAP"TRUE";
"B \NAC \NWC"1;
"S \NAC"
BN"26"143;
%"TAP"
"1","(-3350,4300)","0","mstr_standard","I189";
;
CDS_LIB"mstr_standard"
BODY_TYPE"PLUMBING"
HDL_TAP"TRUE";
"B \NAC \NWC"1;
"S \NAC"
BN"29"137;
%"TAP"
"1","(-3350,4350)","0","mstr_standard","I190";
;
CDS_LIB"mstr_standard"
BODY_TYPE"PLUMBING"
HDL_TAP"TRUE";
"B \NAC \NWC"1;
"S \NAC"
BN"28"139;
%"TAP"
"1","(-3350,4250)","0","mstr_standard","I191";
;
CDS_LIB"mstr_standard"
BODY_TYPE"PLUMBING"
HDL_TAP"TRUE";
"B \NAC \NWC"1;
"S \NAC"
BN"30"133;
%"TAP"
"1","(-3350,4100)","0","mstr_standard","I192";
;
CDS_LIB"mstr_standard"
BODY_TYPE"PLUMBING"
HDL_TAP"TRUE";
"B \NAC \NWC"2;
"S \NAC"
BN"0"134;
%"TAP"
"1","(-3350,4200)","0","mstr_standard","I193";
;
CDS_LIB"mstr_standard"
BODY_TYPE"PLUMBING"
HDL_TAP"TRUE";
"B \NAC \NWC"1;
"S \NAC"
BN"31"132;
%"TAP"
"1","(-3350,4000)","0","mstr_standard","I196";
;
CDS_LIB"mstr_standard"
BODY_TYPE"PLUMBING"
HDL_TAP"TRUE";
"B \NAC \NWC"2;
"S \NAC"
BN"2"117;
%"TAP"
"1","(-3350,4050)","0","mstr_standard","I197";
;
CDS_LIB"mstr_standard"
BODY_TYPE"PLUMBING"
HDL_TAP"TRUE";
"B \NAC \NWC"2;
"S \NAC"
BN"1"119;
%"TAP"
"1","(-3350,3950)","0","mstr_standard","I198";
;
CDS_LIB"mstr_standard"
BODY_TYPE"PLUMBING"
HDL_TAP"TRUE";
"B \NAC \NWC"2;
"S \NAC"
BN"3"115;
%"TAP"
"1","(-3350,3900)","0","mstr_standard","I199";
;
CDS_LIB"mstr_standard"
BODY_TYPE"PLUMBING"
HDL_TAP"TRUE";
"B \NAC \NWC"2;
"S \NAC"
BN"4"113;
%"TAP"
"1","(-3350,3850)","0","mstr_standard","I200";
;
CDS_LIB"mstr_standard"
BODY_TYPE"PLUMBING"
HDL_TAP"TRUE";
"B \NAC \NWC"2;
"S \NAC"
BN"5"112;
%"TAP"
"1","(-3350,3750)","0","mstr_standard","I201";
;
CDS_LIB"mstr_standard"
BODY_TYPE"PLUMBING"
HDL_TAP"TRUE";
"B \NAC \NWC"2;
"S \NAC"
BN"7"110;
%"TAP"
"1","(-3350,3650)","0","mstr_standard","I202";
;
CDS_LIB"mstr_standard"
BODY_TYPE"PLUMBING"
HDL_TAP"TRUE";
"B \NAC \NWC"2;
"S \NAC"
BN"8"109;
%"TAP"
"1","(-3350,3800)","0","mstr_standard","I203";
;
CDS_LIB"mstr_standard"
BODY_TYPE"PLUMBING"
HDL_TAP"TRUE";
"B \NAC \NWC"2;
"S \NAC"
BN"6"111;
%"TAP"
"1","(-3350,3600)","0","mstr_standard","I204";
;
CDS_LIB"mstr_standard"
BODY_TYPE"PLUMBING"
HDL_TAP"TRUE";
"B \NAC \NWC"2;
"S \NAC"
BN"9"108;
%"TAP"
"1","(-3350,3550)","0","mstr_standard","I205";
;
CDS_LIB"mstr_standard"
BODY_TYPE"PLUMBING"
HDL_TAP"TRUE";
"B \NAC \NWC"2;
"S \NAC"
BN"10"125;
%"TAP"
"1","(-3350,3500)","0","mstr_standard","I206";
;
CDS_LIB"mstr_standard"
BODY_TYPE"PLUMBING"
HDL_TAP"TRUE";
"B \NAC \NWC"2;
"S \NAC"
BN"11"124;
%"TAP"
"1","(-3350,3350)","0","mstr_standard","I207";
;
CDS_LIB"mstr_standard"
BODY_TYPE"PLUMBING"
HDL_TAP"TRUE";
"B \NAC \NWC"2;
"S \NAC"
BN"14"121;
%"TAP"
"1","(-3350,3400)","0","mstr_standard","I208";
;
CDS_LIB"mstr_standard"
BODY_TYPE"PLUMBING"
HDL_TAP"TRUE";
"B \NAC \NWC"2;
"S \NAC"
BN"13"122;
%"TAP"
"1","(-3350,3450)","0","mstr_standard","I209";
;
CDS_LIB"mstr_standard"
BODY_TYPE"PLUMBING"
HDL_TAP"TRUE";
"B \NAC \NWC"2;
"S \NAC"
BN"12"123;
%"TAP"
"1","(-3350,3150)","0","mstr_standard","I210";
;
CDS_LIB"mstr_standard"
BODY_TYPE"PLUMBING"
HDL_TAP"TRUE";
"B \NAC \NWC"2;
"S \NAC"
BN"17"116;
%"TAP"
"1","(-3350,3200)","0","mstr_standard","I211";
;
CDS_LIB"mstr_standard"
BODY_TYPE"PLUMBING"
HDL_TAP"TRUE";
"B \NAC \NWC"2;
"S \NAC"
BN"16"118;
%"TAP"
"1","(-3350,3300)","0","mstr_standard","I212";
;
CDS_LIB"mstr_standard"
BODY_TYPE"PLUMBING"
HDL_TAP"TRUE";
"B \NAC \NWC"2;
"S \NAC"
BN"15"120;
%"TAP"
"1","(-3350,3100)","0","mstr_standard","I213";
;
CDS_LIB"mstr_standard"
BODY_TYPE"PLUMBING"
HDL_TAP"TRUE";
"B \NAC \NWC"2;
"S \NAC"
BN"18"114;
%"TAP"
"1","(-3350,2950)","0","mstr_standard","I214";
;
CDS_LIB"mstr_standard"
BODY_TYPE"PLUMBING"
HDL_TAP"TRUE";
"B \NAC \NWC"2;
"S \NAC"
BN"21"105;
%"TAP"
"1","(-3350,3050)","0","mstr_standard","I215";
;
CDS_LIB"mstr_standard"
BODY_TYPE"PLUMBING"
HDL_TAP"TRUE";
"B \NAC \NWC"2;
"S \NAC"
BN"19"96;
%"TAP"
"1","(-3350,3000)","0","mstr_standard","I216";
;
CDS_LIB"mstr_standard"
BODY_TYPE"PLUMBING"
HDL_TAP"TRUE";
"B \NAC \NWC"2;
"S \NAC"
BN"20"106;
%"TAP"
"1","(-3350,2850)","0","mstr_standard","I217";
;
CDS_LIB"mstr_standard"
BODY_TYPE"PLUMBING"
HDL_TAP"TRUE";
"B \NAC \NWC"2;
"S \NAC"
BN"23"103;
%"TAP"
"1","(-3350,2900)","0","mstr_standard","I218";
;
CDS_LIB"mstr_standard"
BODY_TYPE"PLUMBING"
HDL_TAP"TRUE";
"B \NAC \NWC"2;
"S \NAC"
BN"22"104;
%"TAP"
"1","(-3350,2650)","0","mstr_standard","I219";
;
CDS_LIB"mstr_standard"
BODY_TYPE"PLUMBING"
HDL_TAP"TRUE";
"B \NAC \NWC"2;
"S \NAC"
BN"26"100;
%"TAP"
"1","(-3350,2700)","0","mstr_standard","I220";
;
CDS_LIB"mstr_standard"
BODY_TYPE"PLUMBING"
HDL_TAP"TRUE";
"B \NAC \NWC"2;
"S \NAC"
BN"25"101;
%"TAP"
"1","(-3350,2750)","0","mstr_standard","I221";
;
CDS_LIB"mstr_standard"
BODY_TYPE"PLUMBING"
HDL_TAP"TRUE";
"B \NAC \NWC"2;
"S \NAC"
BN"24"102;
%"TAP"
"1","(-3350,2600)","0","mstr_standard","I222";
;
CDS_LIB"mstr_standard"
BODY_TYPE"PLUMBING"
HDL_TAP"TRUE";
"B \NAC \NWC"2;
"S \NAC"
BN"27"99;
%"TAP"
"1","(-3350,2400)","0","mstr_standard","I223";
;
CDS_LIB"mstr_standard"
BODY_TYPE"PLUMBING"
HDL_TAP"TRUE";
"B \NAC \NWC"2;
"S \NAC"
BN"31"107;
%"TAP"
"1","(-3350,2550)","0","mstr_standard","I224";
;
CDS_LIB"mstr_standard"
BODY_TYPE"PLUMBING"
HDL_TAP"TRUE";
"B \NAC \NWC"2;
"S \NAC"
BN"28"98;
%"TAP"
"1","(-3350,2500)","0","mstr_standard","I225";
;
CDS_LIB"mstr_standard"
BODY_TYPE"PLUMBING"
HDL_TAP"TRUE";
"B \NAC \NWC"2;
"S \NAC"
BN"29"97;
%"TAP"
"1","(-3350,2450)","0","mstr_standard","I226";
;
CDS_LIB"mstr_standard"
BODY_TYPE"PLUMBING"
HDL_TAP"TRUE";
"B \NAC \NWC"2;
"S \NAC"
BN"30"90;
%"TAP"
"1","(-3350,2250)","0","mstr_standard","I227";
;
CDS_LIB"mstr_standard"
BODY_TYPE"PLUMBING"
HDL_TAP"TRUE";
"B \NAC \NWC"3;
"S \NAC"
BN"1"94;
%"TAP"
"1","(-3350,2300)","0","mstr_standard","I228";
;
CDS_LIB"mstr_standard"
BODY_TYPE"PLUMBING"
HDL_TAP"TRUE";
"B \NAC \NWC"3;
"S \NAC"
BN"0"95;
%"TAP"
"1","(-3350,2200)","0","mstr_standard","I229";
;
CDS_LIB"mstr_standard"
BODY_TYPE"PLUMBING"
HDL_TAP"TRUE";
"B \NAC \NWC"3;
"S \NAC"
BN"2"93;
%"TAP"
"1","(-3350,2150)","0","mstr_standard","I230";
;
CDS_LIB"mstr_standard"
BODY_TYPE"PLUMBING"
HDL_TAP"TRUE";
"B \NAC \NWC"3;
"S \NAC"
BN"3"92;
%"TAP"
"1","(-3350,2050)","0","mstr_standard","I231";
;
CDS_LIB"mstr_standard"
BODY_TYPE"PLUMBING"
HDL_TAP"TRUE";
"B \NAC \NWC"3;
"S \NAC"
BN"5"89;
%"TAP"
"1","(-3350,2100)","0","mstr_standard","I232";
;
CDS_LIB"mstr_standard"
BODY_TYPE"PLUMBING"
HDL_TAP"TRUE";
"B \NAC \NWC"3;
"S \NAC"
BN"4"91;
%"TAP"
"1","(-3350,1950)","0","mstr_standard","I234";
;
CDS_LIB"mstr_standard"
BODY_TYPE"PLUMBING"
HDL_TAP"TRUE";
"B \NAC \NWC"3;
"S \NAC"
BN"7"85;
%"TAP"
"1","(-3350,1850)","0","mstr_standard","I235";
;
CDS_LIB"mstr_standard"
BODY_TYPE"PLUMBING"
HDL_TAP"TRUE";
"B \NAC \NWC"4;
"S \NAC"
BN"0"88;
%"TAP"
"1","(-3350,2000)","0","mstr_standard","I236";
;
CDS_LIB"mstr_standard"
BODY_TYPE"PLUMBING"
HDL_TAP"TRUE";
"B \NAC \NWC"3;
"S \NAC"
BN"6"87;
%"TAP"
"1","(-3350,1800)","0","mstr_standard","I237";
;
CDS_LIB"mstr_standard"
BODY_TYPE"PLUMBING"
HDL_TAP"TRUE";
"B \NAC \NWC"4;
"S \NAC"
BN"1"86;
%"TAP"
"1","(-3350,1750)","0","mstr_standard","I238";
;
CDS_LIB"mstr_standard"
BODY_TYPE"PLUMBING"
HDL_TAP"TRUE";
"B \NAC \NWC"4;
"S \NAC"
BN"2"84;
%"TAP"
"1","(-3350,1700)","0","mstr_standard","I239";
;
CDS_LIB"mstr_standard"
BODY_TYPE"PLUMBING"
HDL_TAP"TRUE";
"B \NAC \NWC"4;
"S \NAC"
BN"3"83;
%"TAP"
"1","(-3350,1600)","0","mstr_standard","I240";
;
CDS_LIB"mstr_standard"
BODY_TYPE"PLUMBING"
HDL_TAP"TRUE";
"B \NAC \NWC"4;
"S \NAC"
BN"5"81;
%"TAP"
"1","(-3350,1550)","0","mstr_standard","I241";
;
CDS_LIB"mstr_standard"
BODY_TYPE"PLUMBING"
HDL_TAP"TRUE";
"B \NAC \NWC"4;
"S \NAC"
BN"6"80;
%"TAP"
"1","(-3350,1650)","0","mstr_standard","I242";
;
CDS_LIB"mstr_standard"
BODY_TYPE"PLUMBING"
HDL_TAP"TRUE";
"B \NAC \NWC"4;
"S \NAC"
BN"4"82;
%"TAP"
"1","(-3350,1500)","0","mstr_standard","I243";
;
CDS_LIB"mstr_standard"
BODY_TYPE"PLUMBING"
HDL_TAP"TRUE";
"B \NAC \NWC"4;
"S \NAC"
BN"7"79;
%"TAP"
"1","(-5775,5900)","2","mstr_standard","I244";
;
CDS_LIB"mstr_standard"
BODY_TYPE"PLUMBING"
HDL_TAP"TRUE";
"B \NAC \NWC"6;
"S \NAC"
BN"0"75;
%"TAP"
"1","(-5775,5800)","2","mstr_standard","I245";
;
CDS_LIB"mstr_standard"
BODY_TYPE"PLUMBING"
HDL_TAP"TRUE";
"B \NAC \NWC"6;
"S \NAC"
BN"1"73;
%"TAP"
"1","(-5775,5700)","2","mstr_standard","I246";
;
CDS_LIB"mstr_standard"
BODY_TYPE"PLUMBING"
HDL_TAP"TRUE";
"B \NAC \NWC"6;
"S \NAC"
BN"2"71;
%"TAP"
"1","(-5975,5650)","2","mstr_standard","I247";
;
CDS_LIB"mstr_standard"
BODY_TYPE"PLUMBING"
HDL_TAP"TRUE";
"B \NAC \NWC"5;
"S \NAC"
BN"2"78;
%"TAP"
"1","(-5975,5750)","2","mstr_standard","I248";
;
CDS_LIB"mstr_standard"
BODY_TYPE"PLUMBING"
HDL_TAP"TRUE";
"B \NAC \NWC"5;
"S \NAC"
BN"1"63;
%"TAP"
"1","(-5975,5850)","2","mstr_standard","I249";
;
CDS_LIB"mstr_standard"
BODY_TYPE"PLUMBING"
HDL_TAP"TRUE";
"B \NAC \NWC"5;
"S \NAC"
BN"0"64;
%"TAP"
"1","(-5775,5600)","2","mstr_standard","I250";
;
CDS_LIB"mstr_standard"
BODY_TYPE"PLUMBING"
HDL_TAP"TRUE";
"B \NAC \NWC"6;
"S \NAC"
BN"3"69;
%"TAP"
"1","(-5775,5500)","2","mstr_standard","I251";
;
CDS_LIB"mstr_standard"
BODY_TYPE"PLUMBING"
HDL_TAP"TRUE";
"B \NAC \NWC"6;
"S \NAC"
BN"4"68;
%"TAP"
"1","(-5775,5400)","2","mstr_standard","I252";
;
CDS_LIB"mstr_standard"
BODY_TYPE"PLUMBING"
HDL_TAP"TRUE";
"B \NAC \NWC"6;
"S \NAC"
BN"5"67;
%"TAP"
"1","(-5775,5300)","2","mstr_standard","I253";
;
CDS_LIB"mstr_standard"
BODY_TYPE"PLUMBING"
HDL_TAP"TRUE";
"B \NAC \NWC"6;
"S \NAC"
BN"6"66;
%"TAP"
"1","(-5775,5200)","2","mstr_standard","I254";
;
CDS_LIB"mstr_standard"
BODY_TYPE"PLUMBING"
HDL_TAP"TRUE";
"B \NAC \NWC"6;
"S \NAC"
BN"7"65;
%"TAP"
"1","(-5975,5550)","2","mstr_standard","I255";
;
CDS_LIB"mstr_standard"
BODY_TYPE"PLUMBING"
HDL_TAP"TRUE";
"B \NAC \NWC"5;
"S \NAC"
BN"3"77;
%"TAP"
"1","(-5975,5450)","2","mstr_standard","I256";
;
CDS_LIB"mstr_standard"
BODY_TYPE"PLUMBING"
HDL_TAP"TRUE";
"B \NAC \NWC"5;
"S \NAC"
BN"4"76;
%"TAP"
"1","(-5975,5350)","2","mstr_standard","I257";
;
CDS_LIB"mstr_standard"
BODY_TYPE"PLUMBING"
HDL_TAP"TRUE";
"B \NAC \NWC"5;
"S \NAC"
BN"5"74;
%"TAP"
"1","(-5975,5250)","2","mstr_standard","I258";
;
CDS_LIB"mstr_standard"
BODY_TYPE"PLUMBING"
HDL_TAP"TRUE";
"B \NAC \NWC"5;
"S \NAC"
BN"6"72;
%"TAP"
"1","(-5975,5150)","2","mstr_standard","I259";
;
CDS_LIB"mstr_standard"
BODY_TYPE"PLUMBING"
HDL_TAP"TRUE";
"B \NAC \NWC"5;
"S \NAC"
BN"7"70;
%"TAP"
"1","(-5775,5100)","2","mstr_standard","I260";
;
CDS_LIB"mstr_standard"
BODY_TYPE"PLUMBING"
HDL_TAP"TRUE";
"B \NAC \NWC"6;
"S \NAC"
BN"8"50;
%"TAP"
"1","(-5775,5000)","2","mstr_standard","I261";
;
CDS_LIB"mstr_standard"
BODY_TYPE"PLUMBING"
HDL_TAP"TRUE";
"B \NAC \NWC"6;
"S \NAC"
BN"9"47;
%"TAP"
"1","(-5775,4850)","2","mstr_standard","I262";
;
CDS_LIB"mstr_standard"
BODY_TYPE"PLUMBING"
HDL_TAP"TRUE";
"B \NAC \NWC"8;
"S \NAC"
BN"0"55;
%"TAP"
"1","(-5775,4750)","2","mstr_standard","I263";
;
CDS_LIB"mstr_standard"
BODY_TYPE"PLUMBING"
HDL_TAP"TRUE";
"B \NAC \NWC"8;
"S \NAC"
BN"1"53;
%"TAP"
"1","(-5775,4650)","2","mstr_standard","I264";
;
CDS_LIB"mstr_standard"
BODY_TYPE"PLUMBING"
HDL_TAP"TRUE";
"B \NAC \NWC"8;
"S \NAC"
BN"2"51;
%"TAP"
"1","(-5975,5050)","2","mstr_standard","I265";
;
CDS_LIB"mstr_standard"
BODY_TYPE"PLUMBING"
HDL_TAP"TRUE";
"B \NAC \NWC"5;
"S \NAC"
BN"8"59;
%"TAP"
"1","(-5975,4950)","2","mstr_standard","I266";
;
CDS_LIB"mstr_standard"
BODY_TYPE"PLUMBING"
HDL_TAP"TRUE";
"B \NAC \NWC"5;
"S \NAC"
BN"9"57;
%"TAP"
"1","(-5975,4800)","2","mstr_standard","I267";
;
CDS_LIB"mstr_standard"
BODY_TYPE"PLUMBING"
HDL_TAP"TRUE";
"B \NAC \NWC"7;
"S \NAC"
BN"0"62;
%"TAP"
"1","(-5975,4700)","2","mstr_standard","I268";
;
CDS_LIB"mstr_standard"
BODY_TYPE"PLUMBING"
HDL_TAP"TRUE";
"B \NAC \NWC"7;
"S \NAC"
BN"1"61;
%"TAP"
"1","(-5775,4550)","2","mstr_standard","I269";
;
CDS_LIB"mstr_standard"
BODY_TYPE"PLUMBING"
HDL_TAP"TRUE";
"B \NAC \NWC"8;
"S \NAC"
BN"3"48;
%"TAP"
"1","(-5775,4450)","2","mstr_standard","I270";
;
CDS_LIB"mstr_standard"
BODY_TYPE"PLUMBING"
HDL_TAP"TRUE";
"B \NAC \NWC"8;
"S \NAC"
BN"4"46;
%"TAP"
"1","(-5975,4600)","2","mstr_standard","I271";
;
CDS_LIB"mstr_standard"
BODY_TYPE"PLUMBING"
HDL_TAP"TRUE";
"B \NAC \NWC"7;
"S \NAC"
BN"2"60;
%"TAP"
"1","(-5775,4350)","2","mstr_standard","I272";
;
CDS_LIB"mstr_standard"
BODY_TYPE"PLUMBING"
HDL_TAP"TRUE";
"B \NAC \NWC"8;
"S \NAC"
BN"5"45;
%"TAP"
"1","(-5775,4250)","2","mstr_standard","I273";
;
CDS_LIB"mstr_standard"
BODY_TYPE"PLUMBING"
HDL_TAP"TRUE";
"B \NAC \NWC"8;
"S \NAC"
BN"6"44;
%"TAP"
"1","(-5775,4150)","2","mstr_standard","I274";
;
CDS_LIB"mstr_standard"
BODY_TYPE"PLUMBING"
HDL_TAP"TRUE";
"B \NAC \NWC"8;
"S \NAC"
BN"7"43;
%"TAP"
"1","(-5975,4500)","2","mstr_standard","I275";
;
CDS_LIB"mstr_standard"
BODY_TYPE"PLUMBING"
HDL_TAP"TRUE";
"B \NAC \NWC"7;
"S \NAC"
BN"3"58;
%"TAP"
"1","(-5975,4400)","2","mstr_standard","I276";
;
CDS_LIB"mstr_standard"
BODY_TYPE"PLUMBING"
HDL_TAP"TRUE";
"B \NAC \NWC"7;
"S \NAC"
BN"4"56;
%"TAP"
"1","(-5975,4300)","2","mstr_standard","I277";
;
CDS_LIB"mstr_standard"
BODY_TYPE"PLUMBING"
HDL_TAP"TRUE";
"B \NAC \NWC"7;
"S \NAC"
BN"5"54;
%"TAP"
"1","(-5975,4200)","2","mstr_standard","I278";
;
CDS_LIB"mstr_standard"
BODY_TYPE"PLUMBING"
HDL_TAP"TRUE";
"B \NAC \NWC"7;
"S \NAC"
BN"6"52;
%"TAP"
"1","(-5975,4100)","2","mstr_standard","I279";
;
CDS_LIB"mstr_standard"
BODY_TYPE"PLUMBING"
HDL_TAP"TRUE";
"B \NAC \NWC"7;
"S \NAC"
BN"7"49;
%"TAP"
"1","(-5775,4050)","2","mstr_standard","I284";
;
CDS_LIB"mstr_standard"
BODY_TYPE"PLUMBING"
HDL_TAP"TRUE";
"B \NAC \NWC"8;
"S \NAC"
BN"8"27;
%"TAP"
"1","(-5775,3950)","2","mstr_standard","I285";
;
CDS_LIB"mstr_standard"
BODY_TYPE"PLUMBING"
HDL_TAP"TRUE";
"B \NAC \NWC"8;
"S \NAC"
BN"9"26;
%"TAP"
"1","(-5975,4000)","2","mstr_standard","I286";
;
CDS_LIB"mstr_standard"
BODY_TYPE"PLUMBING"
HDL_TAP"TRUE";
"B \NAC \NWC"7;
"S \NAC"
BN"8"29;
%"TAP"
"1","(-5975,3900)","2","mstr_standard","I287";
;
CDS_LIB"mstr_standard"
BODY_TYPE"PLUMBING"
HDL_TAP"TRUE";
"B \NAC \NWC"7;
"S \NAC"
BN"9"28;
%"TAP"
"1","(-5975,3750)","2","mstr_standard","I288";
;
CDS_LIB"mstr_standard"
BODY_TYPE"PLUMBING"
HDL_TAP"TRUE";
"B \NAC \NWC"9;
"S \NAC"
BN"0"42;
%"TAP"
"1","(-5975,3700)","2","mstr_standard","I289";
;
CDS_LIB"mstr_standard"
BODY_TYPE"PLUMBING"
HDL_TAP"TRUE";
"B \NAC \NWC"9;
"S \NAC"
BN"1"40;
%"TAP"
"1","(-5975,3650)","2","mstr_standard","I290";
;
CDS_LIB"mstr_standard"
BODY_TYPE"PLUMBING"
HDL_TAP"TRUE";
"B \NAC \NWC"9;
"S \NAC"
BN"2"38;
%"TAP"
"1","(-5975,3600)","2","mstr_standard","I291";
;
CDS_LIB"mstr_standard"
BODY_TYPE"PLUMBING"
HDL_TAP"TRUE";
"B \NAC \NWC"9;
"S \NAC"
BN"3"36;
%"TAP"
"1","(-5975,3500)","2","mstr_standard","I292";
;
CDS_LIB"mstr_standard"
BODY_TYPE"PLUMBING"
HDL_TAP"TRUE";
"B \NAC \NWC"9;
"S \NAC"
BN"5"32;
%"TAP"
"1","(-5975,3550)","2","mstr_standard","I293";
;
CDS_LIB"mstr_standard"
BODY_TYPE"PLUMBING"
HDL_TAP"TRUE";
"B \NAC \NWC"9;
"S \NAC"
BN"4"34;
%"TAP"
"1","(-5975,3450)","2","mstr_standard","I294";
;
CDS_LIB"mstr_standard"
BODY_TYPE"PLUMBING"
HDL_TAP"TRUE";
"B \NAC \NWC"9;
"S \NAC"
BN"6"30;
%"TAP"
"1","(-5975,3350)","2","mstr_standard","I295";
;
CDS_LIB"mstr_standard"
BODY_TYPE"PLUMBING"
HDL_TAP"TRUE";
"B \NAC \NWC"10;
"S \NAC"
BN"0"41;
%"TAP"
"1","(-5975,3250)","2","mstr_standard","I296";
;
CDS_LIB"mstr_standard"
BODY_TYPE"PLUMBING"
HDL_TAP"TRUE";
"B \NAC \NWC"10;
"S \NAC"
BN"2"37;
%"TAP"
"1","(-5975,3300)","2","mstr_standard","I297";
;
CDS_LIB"mstr_standard"
BODY_TYPE"PLUMBING"
HDL_TAP"TRUE";
"B \NAC \NWC"10;
"S \NAC"
BN"1"39;
%"TAP"
"1","(-5975,3200)","2","mstr_standard","I298";
;
CDS_LIB"mstr_standard"
BODY_TYPE"PLUMBING"
HDL_TAP"TRUE";
"B \NAC \NWC"10;
"S \NAC"
BN"3"35;
%"TAP"
"1","(-5975,3100)","2","mstr_standard","I299";
;
CDS_LIB"mstr_standard"
BODY_TYPE"PLUMBING"
HDL_TAP"TRUE";
"B \NAC \NWC"10;
"S \NAC"
BN"5"31;
%"TAP"
"1","(-5975,3150)","2","mstr_standard","I300";
;
CDS_LIB"mstr_standard"
BODY_TYPE"PLUMBING"
HDL_TAP"TRUE";
"B \NAC \NWC"10;
"S \NAC"
BN"4"33;
%"TAP"
"1","(-5975,3050)","2","mstr_standard","I301";
;
CDS_LIB"mstr_standard"
BODY_TYPE"PLUMBING"
HDL_TAP"TRUE";
"B \NAC \NWC"10;
"S \NAC"
BN"6"25;
%"Q_RES"
"1","(-6650,2050)","0","pure_quanta","I314";
;
LOCATION"R507"
$SEC"1"
CDS_SEC"1"
PACK_TYPE"0402LF"
TOLERANCE"1%"
VALUE"15"
MATERIAL"CHIP"
WATTAGE"1/16W"
CDS_LIB"pure_quanta"
PART_NUMBER"CS01502FB03";
"B"
$PN"2"12;
"A"
$PN"1"11;
END.
